(kicad_pcb
	(version 20260206)
	(generator "pcbnew")
	(generator_version "10.0")
	(general
		(thickness 1.6)
		(legacy_teardrops no)
	)
	(paper "A4")
	(title_block
		(title "peb — Lightning_PEB_BRD.brd")
		(comment 1 "Lightning (Wiwynn / Facebook NVMe JBOF) / footprints 1675-1684 of 2563")
	)
	(layers
		(0 "F.Cu" signal "TOP")
		(4 "In1.Cu" signal "L2GND")
		(6 "In2.Cu" signal "L3")
		(8 "In3.Cu" signal "L4VCC")
		(10 "In4.Cu" signal "L5VCC")
		(12 "In5.Cu" signal "L6")
		(14 "In6.Cu" signal "L7GND")
		(2 "B.Cu" signal "BOTTOM")
		(9 "F.Adhes" user "F.Adhesive")
		(11 "B.Adhes" user "B.Adhesive")
		(13 "F.Paste" user "Package Geometry/Pastemask Top")
		(15 "B.Paste" user "Package Geometry/Pastemask Bottom")
		(5 "F.SilkS" user "Ref Des/Silkscreen Top")
		(7 "B.SilkS" user "Ref Des/Silkscreen Bottom")
		(1 "F.Mask" user "Board Geometry/Soldermask Top")
		(3 "B.Mask" user "Board Geometry/Soldermask Bottom")
		(17 "Dwgs.User" user "User.Drawings")
		(19 "Cmts.User" user "User.Comments")
		(21 "Eco1.User" user "User.Eco1")
		(23 "Eco2.User" user "User.Eco2")
		(25 "Edge.Cuts" user "Board Geometry/Outline")
		(27 "Margin" user)
		(31 "F.CrtYd" user "Package Geometry/Place Bound Top")
		(29 "B.CrtYd" user "Package Geometry/Place Bound Bottom")
		(35 "F.Fab" user "Ref Des/Assembly Top")
		(33 "B.Fab" user "Ref Des/Assembly Bottom")
	)
	(footprint ""
		(layer "B.Cu")
		(at 130.51028 -33.54578)
		(property "Reference" "R2925"
			(at 0 0 0)
			(layer "B.SilkS")
			(hide yes)
			(effects
				(font
					(size 1.27 1.27)
				)
				(justify mirror)
			)
		)
		(property "Value" "0R2J-2-GP"
			(at -0.064008 -3.993896 0)
			(unlocked yes)
			(layer "B.Fab")
			(hide yes)
			(effects
				(font
					(size 1.016 1.016)
					(thickness 0.1524)
				)
				(justify mirror)
			)
		)
		(property "Device Type" "R402H16"
			(at -0.064008 -5.517896 0)
			(unlocked yes)
			(layer "B.Fab")
			(hide yes)
			(effects
				(font
					(size 1.016 1.016)
					(thickness 0.1524)
				)
				(justify mirror)
			)
		)
		(duplicate_pad_numbers_are_jumpers no)
		(fp_line
			(start -0.508 -0.9398)
			(end 0.508 -0.9398)
			(stroke
				(width 0.1524)
				(type default)
			)
			(layer "B.SilkS")
		)
		(fp_line
			(start 0.508 -0.9398)
			(end 0.508 0.9398)
			(stroke
				(width 0.1524)
				(type default)
			)
			(layer "B.SilkS")
		)
		(fp_rect
			(start 0.508 0.9398)
			(end -0.508 -0.9398)
			(stroke
				(width 0)
				(type default)
			)
			(fill no)
			(layer "B.CrtYd")
		)
		(fp_rect
			(start 0.508 0.9398)
			(end -0.508 -0.9398)
			(stroke
				(width 0)
				(type default)
			)
			(fill no)
			(layer "B.Fab")
		)
		(pad "1" smd custom
			(at 0 -0.4445 180)
			(size 0.1397 0.1397)
			(layers "B.Cu" "B.Mask" "B.Paste")
			(net "CBL_PRSNT_N_1")
			(options
				(clearance outline)
				(anchor circle)
			)
			(primitives
				(gr_poly
					(pts
						(arc
							(start -0.1778 0.2794)
							(mid -0.249642 0.249642)
							(end -0.2794 0.1778)
						)
						(arc
							(start -0.2794 -0.1778)
							(mid -0.249642 -0.249642)
							(end -0.1778 -0.2794)
						)
						(arc
							(start 0.1778 -0.2794)
							(mid 0.249642 -0.249642)
							(end 0.2794 -0.1778)
						)
						(arc
							(start 0.2794 0.1778)
							(mid 0.249642 0.249642)
							(end 0.1778 0.2794)
						)
					)
					(width 0)
					(fill yes)
				)
			)
		)
		(pad "2" smd custom
			(at 0 0.4445 180)
			(size 0.1397 0.1397)
			(layers "B.Cu" "B.Mask" "B.Paste")
			(net "8644_SDA_R_1")
			(options
				(clearance outline)
				(anchor circle)
			)
			(primitives
				(gr_poly
					(pts
						(arc
							(start -0.1778 0.2794)
							(mid -0.249642 0.249642)
							(end -0.2794 0.1778)
						)
						(arc
							(start -0.2794 -0.1778)
							(mid -0.249642 -0.249642)
							(end -0.1778 -0.2794)
						)
						(arc
							(start 0.1778 -0.2794)
							(mid 0.249642 -0.249642)
							(end 0.2794 -0.1778)
						)
						(arc
							(start 0.2794 0.1778)
							(mid 0.249642 0.249642)
							(end 0.1778 0.2794)
						)
					)
					(width 0)
					(fill yes)
				)
			)
		)
	)
	(footprint ""
		(layer "B.Cu")
		(at 246.599964 -40.999918 -90)
		(property "Reference" "TP288"
			(at 0 0 90)
			(layer "B.SilkS")
			(hide yes)
			(effects
				(font
					(size 1.27 1.27)
				)
				(justify mirror)
			)
		)
		(property "Value" "TPAD28-2-GP"
			(at 0.0127 -1.6637 270)
			(unlocked yes)
			(layer "B.Fab")
			(hide yes)
			(effects
				(font
					(size 1.016 1.016)
					(thickness 0.1524)
				)
				(justify mirror)
			)
		)
		(property "Device Type" "TPAD28"
			(at 0.0127 -3.1877 270)
			(unlocked yes)
			(layer "B.Fab")
			(hide yes)
			(effects
				(font
					(size 1.016 1.016)
					(thickness 0.1524)
				)
				(justify mirror)
			)
		)
		(duplicate_pad_numbers_are_jumpers no)
		(fp_poly
			(pts
				(arc
					(start 0 -0.3556)
					(mid 0 0.3556)
					(end 0 -0.3556)
				)
			)
			(stroke
				(width 0)
				(type default)
			)
			(fill no)
			(layer "B.CrtYd")
		)
		(fp_poly
			(pts
				(arc
					(start 0 -0.6096)
					(mid 0 0.6096)
					(end 0 -0.6096)
				)
			)
			(stroke
				(width 0)
				(type default)
			)
			(fill no)
			(layer "B.Fab")
		)
		(pad "1" smd circle
			(at 0 0 90)
			(size 0.7112 0.7112)
			(layers "B.Cu" "B.Mask" "B.Paste")
			(net "TWI_SRST#5")
		)
	)
	(footprint ""
		(layer "B.Cu")
		(at 310.007 -66.167 180)
		(property "Reference" "PG67"
			(at 0 0 0)
			(layer "B.SilkS")
			(hide yes)
			(effects
				(font
					(size 1.27 1.27)
				)
				(justify mirror)
			)
		)
		(property "Value" "GAP-CLOSE-PWR-3-GP"
			(at -0.0254 -6.5786 180)
			(unlocked yes)
			(layer "B.Fab")
			(hide yes)
			(effects
				(font
					(size 1.016 1.016)
					(thickness 0.1524)
				)
				(justify mirror)
			)
		)
		(property "Device Type" "GAP-CLOSE-PWR-3"
			(at -0.0254 -8.255 180)
			(unlocked yes)
			(layer "B.Fab")
			(hide yes)
			(effects
				(font
					(size 1.016 1.016)
					(thickness 0.1524)
				)
				(justify mirror)
			)
		)
		(duplicate_pad_numbers_are_jumpers no)
		(fp_rect
			(start 0.7112 0.4572)
			(end -0.7112 -0.4572)
			(stroke
				(width 0)
				(type default)
			)
			(fill no)
			(layer "B.CrtYd")
		)
		(fp_poly
			(pts
				(xy 0.7112 -0.4572) (xy -0.7112 -0.4572) (xy -0.7112 0.4572) (xy 0.7112 0.4572)
			)
			(stroke
				(width 0)
				(type default)
			)
			(fill no)
			(layer "B.Fab")
		)
		(pad "1" smd rect
			(at 0.3048 0)
			(size 0.6604 0.762)
			(layers "B.Cu" "B.Mask" "B.Paste")
			(net "DUT_VDD")
		)
		(pad "2" smd rect
			(at -0.3048 0)
			(size 0.6604 0.762)
			(layers "B.Cu" "B.Mask" "B.Paste")
			(net "P0V9_E")
		)
	)
	(footprint ""
		(layer "B.Cu")
		(at 178.9938 -71.628 180)
		(property "Reference" "C617"
			(at 0 0 0)
			(layer "B.SilkS")
			(hide yes)
			(effects
				(font
					(size 1.27 1.27)
				)
				(justify mirror)
			)
		)
		(property "Value" "SC4D7U16V5KX-1-GP"
			(at 0.0762 -6.1214 180)
			(unlocked yes)
			(layer "B.Fab")
			(hide yes)
			(effects
				(font
					(size 1.016 1.016)
					(thickness 0.1524)
				)
				(justify mirror)
			)
		)
		(property "Device Type" "C805H56"
			(at 0.0762 -8.1534 180)
			(unlocked yes)
			(layer "B.Fab")
			(hide yes)
			(effects
				(font
					(size 1.016 1.016)
					(thickness 0.1524)
				)
				(justify mirror)
			)
		)
		(duplicate_pad_numbers_are_jumpers no)
		(fp_line
			(start -0.635 0)
			(end 0.635 0)
			(stroke
				(width 0.508)
				(type default)
			)
			(layer "B.SilkS")
		)
		(fp_rect
			(start 0.9652 1.778)
			(end -0.9652 -1.778)
			(stroke
				(width 0)
				(type default)
			)
			(fill no)
			(layer "B.CrtYd")
		)
		(fp_poly
			(pts
				(xy 0.9652 -1.778) (xy -0.9652 -1.778) (xy -0.9652 1.778) (xy 0.9652 1.778)
			)
			(stroke
				(width 0)
				(type default)
			)
			(fill no)
			(layer "B.Fab")
		)
		(pad "1" smd rect
			(at 0 -0.9652)
			(size 1.397 1.143)
			(layers "B.Cu" "B.Mask" "B.Paste")
			(net "DUT_AVD_PCIE")
		)
		(pad "2" smd rect
			(at 0 0.9652)
			(size 1.397 1.143)
			(layers "B.Cu" "B.Mask" "B.Paste")
			(net "GND")
		)
	)
	(footprint ""
		(layer "B.Cu")
		(at 234.59948 -41.0083)
		(property "Reference" "TP120"
			(at 0 0 0)
			(layer "B.SilkS")
			(hide yes)
			(effects
				(font
					(size 1.27 1.27)
				)
				(justify mirror)
			)
		)
		(property "Value" "TPAD28-2-GP"
			(at 0.0127 -1.6637 0)
			(unlocked yes)
			(layer "B.Fab")
			(hide yes)
			(effects
				(font
					(size 1.016 1.016)
					(thickness 0.1524)
				)
				(justify mirror)
			)
		)
		(property "Device Type" "TPAD28"
			(at 0.0127 -3.1877 0)
			(unlocked yes)
			(layer "B.Fab")
			(hide yes)
			(effects
				(font
					(size 1.016 1.016)
					(thickness 0.1524)
				)
				(justify mirror)
			)
		)
		(duplicate_pad_numbers_are_jumpers no)
		(fp_poly
			(pts
				(arc
					(start 0.3556 0)
					(mid -0.3556 0)
					(end 0.3556 0)
				)
			)
			(stroke
				(width 0)
				(type default)
			)
			(fill no)
			(layer "B.CrtYd")
		)
		(fp_poly
			(pts
				(arc
					(start 0.6096 0)
					(mid -0.6096 0)
					(end 0.6096 0)
				)
			)
			(stroke
				(width 0)
				(type default)
			)
			(fill no)
			(layer "B.Fab")
		)
		(pad "1" smd circle
			(at 0 0 180)
			(size 0.7112 0.7112)
			(layers "B.Cu" "B.Mask" "B.Paste")
			(net "LBI_ADDR_8")
		)
	)
	(footprint ""
		(layer "B.Cu")
		(at 247.651016 -25.424638 90)
		(property "Reference" "TP303"
			(at 0 0 90)
			(layer "B.SilkS")
			(hide yes)
			(effects
				(font
					(size 1.27 1.27)
				)
				(justify mirror)
			)
		)
		(property "Value" "TPAD28-2-GP"
			(at 0.0127 -1.6637 90)
			(unlocked yes)
			(layer "B.Fab")
			(hide yes)
			(effects
				(font
					(size 1.016 1.016)
					(thickness 0.1524)
				)
				(justify mirror)
			)
		)
		(property "Device Type" "TPAD28"
			(at 0.0127 -3.1877 90)
			(unlocked yes)
			(layer "B.Fab")
			(hide yes)
			(effects
				(font
					(size 1.016 1.016)
					(thickness 0.1524)
				)
				(justify mirror)
			)
		)
		(duplicate_pad_numbers_are_jumpers no)
		(fp_poly
			(pts
				(arc
					(start 0 0.3556)
					(mid 0 -0.3556)
					(end 0 0.3556)
				)
			)
			(stroke
				(width 0)
				(type default)
			)
			(fill no)
			(layer "B.CrtYd")
		)
		(fp_poly
			(pts
				(arc
					(start 0 0.6096)
					(mid 0 -0.6096)
					(end 0 0.6096)
				)
			)
			(stroke
				(width 0)
				(type default)
			)
			(fill no)
			(layer "B.Fab")
		)
		(pad "1" smd circle
			(at 0 0 270)
			(size 0.7112 0.7112)
			(layers "B.Cu" "B.Mask" "B.Paste")
			(net "TWI_SCL10")
		)
	)
	(footprint ""
		(layer "B.Cu")
		(at 224.536 -20.447)
		(property "Reference" "R3707"
			(at 0 0 0)
			(layer "B.SilkS")
			(hide yes)
			(effects
				(font
					(size 1.27 1.27)
				)
				(justify mirror)
			)
		)
		(property "Value" "4K7R2F-GP"
			(at -0.064008 -3.993896 0)
			(unlocked yes)
			(layer "B.Fab")
			(hide yes)
			(effects
				(font
					(size 1.016 1.016)
					(thickness 0.1524)
				)
				(justify mirror)
			)
		)
		(property "Device Type" "R402H16"
			(at -0.064008 -5.517896 0)
			(unlocked yes)
			(layer "B.Fab")
			(hide yes)
			(effects
				(font
					(size 1.016 1.016)
					(thickness 0.1524)
				)
				(justify mirror)
			)
		)
		(duplicate_pad_numbers_are_jumpers no)
		(fp_line
			(start -0.508 -0.9398)
			(end 0.508 -0.9398)
			(stroke
				(width 0.1524)
				(type default)
			)
			(layer "B.SilkS")
		)
		(fp_line
			(start 0.508 -0.9398)
			(end 0.508 0.9398)
			(stroke
				(width 0.1524)
				(type default)
			)
			(layer "B.SilkS")
		)
		(fp_rect
			(start 0.508 0.9398)
			(end -0.508 -0.9398)
			(stroke
				(width 0)
				(type default)
			)
			(fill no)
			(layer "B.CrtYd")
		)
		(fp_rect
			(start 0.508 0.9398)
			(end -0.508 -0.9398)
			(stroke
				(width 0)
				(type default)
			)
			(fill no)
			(layer "B.Fab")
		)
		(pad "1" smd custom
			(at 0 -0.4445 180)
			(size 0.1397 0.1397)
			(layers "B.Cu" "B.Mask" "B.Paste")
			(net "HOST6_RST_N_LS")
			(options
				(clearance outline)
				(anchor circle)
			)
			(primitives
				(gr_poly
					(pts
						(arc
							(start -0.1778 0.2794)
							(mid -0.249642 0.249642)
							(end -0.2794 0.1778)
						)
						(arc
							(start -0.2794 -0.1778)
							(mid -0.249642 -0.249642)
							(end -0.1778 -0.2794)
						)
						(arc
							(start 0.1778 -0.2794)
							(mid 0.249642 -0.249642)
							(end 0.2794 -0.1778)
						)
						(arc
							(start 0.2794 0.1778)
							(mid 0.249642 0.249642)
							(end 0.1778 0.2794)
						)
					)
					(width 0)
					(fill yes)
				)
			)
		)
		(pad "2" smd custom
			(at 0 0.4445 180)
			(size 0.1397 0.1397)
			(layers "B.Cu" "B.Mask" "B.Paste")
			(net "DUT_VDDO")
			(options
				(clearance outline)
				(anchor circle)
			)
			(primitives
				(gr_poly
					(pts
						(arc
							(start -0.1778 0.2794)
							(mid -0.249642 0.249642)
							(end -0.2794 0.1778)
						)
						(arc
							(start -0.2794 -0.1778)
							(mid -0.249642 -0.249642)
							(end -0.1778 -0.2794)
						)
						(arc
							(start 0.1778 -0.2794)
							(mid 0.249642 -0.249642)
							(end 0.2794 -0.1778)
						)
						(arc
							(start 0.2794 0.1778)
							(mid 0.249642 0.249642)
							(end 0.1778 0.2794)
						)
					)
					(width 0)
					(fill yes)
				)
			)
		)
	)
	(footprint ""
		(layer "B.Cu")
		(at 253.5936 -36.999672 90)
		(property "Reference" "C593"
			(at 0 0 90)
			(layer "B.SilkS")
			(hide yes)
			(effects
				(font
					(size 1.27 1.27)
				)
				(justify mirror)
			)
		)
		(property "Value" "SCD1U16V1KX-1-GP"
			(at 2.8321 -1.7399 90)
			(unlocked yes)
			(layer "B.Fab")
			(hide yes)
			(effects
				(font
					(size 1.016 1.016)
					(thickness 0.1524)
				)
				(justify mirror)
			)
		)
		(property "Device Type" "C0201H13"
			(at 2.8321 -3.2639 90)
			(unlocked yes)
			(layer "B.Fab")
			(hide yes)
			(effects
				(font
					(size 1.016 1.016)
					(thickness 0.1524)
				)
				(justify mirror)
			)
		)
		(duplicate_pad_numbers_are_jumpers no)
		(fp_rect
			(start 0.2794 0.6477)
			(end -0.2794 -0.6477)
			(stroke
				(width 0)
				(type default)
			)
			(fill no)
			(layer "B.CrtYd")
		)
		(fp_rect
			(start 0.2794 0.6477)
			(end -0.2794 -0.6477)
			(stroke
				(width 0)
				(type default)
			)
			(fill no)
			(layer "B.Fab")
		)
		(pad "1" smd custom
			(at 0 -0.2794 270)
			(size 0.0762 0.0762)
			(layers "B.Cu" "B.Mask" "B.Paste")
			(net "DUT_AVD_PCIE")
			(options
				(clearance outline)
				(anchor circle)
			)
			(primitives
				(gr_poly
					(pts
						(arc
							(start 0.1524 0.127)
							(mid 0.137521 0.162921)
							(end 0.1016 0.1778)
						)
						(arc
							(start -0.1016 0.1778)
							(mid -0.137521 0.162921)
							(end -0.1524 0.127)
						)
						(arc
							(start -0.1524 -0.127)
							(mid -0.137521 -0.162921)
							(end -0.1016 -0.1778)
						)
						(arc
							(start 0.1016 -0.1778)
							(mid 0.137521 -0.162921)
							(end 0.1524 -0.127)
						)
					)
					(width 0)
					(fill yes)
				)
			)
		)
		(pad "2" smd custom
			(at 0 0.2794 270)
			(size 0.0762 0.0762)
			(layers "B.Cu" "B.Mask" "B.Paste")
			(net "GND")
			(options
				(clearance outline)
				(anchor circle)
			)
			(primitives
				(gr_poly
					(pts
						(arc
							(start 0.1524 0.127)
							(mid 0.137521 0.162921)
							(end 0.1016 0.1778)
						)
						(arc
							(start -0.1016 0.1778)
							(mid -0.137521 0.162921)
							(end -0.1524 0.127)
						)
						(arc
							(start -0.1524 -0.127)
							(mid -0.137521 -0.162921)
							(end -0.1016 -0.1778)
						)
						(arc
							(start 0.1016 -0.1778)
							(mid 0.137521 -0.162921)
							(end 0.1524 -0.127)
						)
					)
					(width 0)
					(fill yes)
				)
			)
		)
	)
	(footprint ""
		(layer "B.Cu")
		(at 38.840664 -126.932944 180)
		(property "Reference" "C217"
			(at 0 0 0)
			(layer "B.SilkS")
			(hide yes)
			(effects
				(font
					(size 1.27 1.27)
				)
				(justify mirror)
			)
		)
		(property "Value" "SC1U10V2KX-4-GP"
			(at -1.1811 -2.7051 180)
			(unlocked yes)
			(layer "B.Fab")
			(hide yes)
			(effects
				(font
					(size 1.016 1.016)
					(thickness 0.1524)
				)
				(justify mirror)
			)
		)
		(property "Device Type" "C402H22"
			(at -1.1811 -4.2291 180)
			(unlocked yes)
			(layer "B.Fab")
			(hide yes)
			(effects
				(font
					(size 1.016 1.016)
					(thickness 0.1524)
				)
				(justify mirror)
			)
		)
		(duplicate_pad_numbers_are_jumpers no)
		(fp_rect
			(start 0.4318 0.9525)
			(end -0.4318 -0.9525)
			(stroke
				(width 0)
				(type default)
			)
			(fill no)
			(layer "B.CrtYd")
		)
		(fp_rect
			(start 0.4318 0.9525)
			(end -0.4318 -0.9525)
			(stroke
				(width 0)
				(type default)
			)
			(fill no)
			(layer "B.Fab")
		)
		(pad "1" smd custom
			(at 0 -0.4445)
			(size 0.1524 0.1524)
			(layers "B.Cu" "B.Mask" "B.Paste")
			(net "P3V3_STBY")
			(options
				(clearance outline)
				(anchor circle)
			)
			(primitives
				(gr_poly
					(pts
						(arc
							(start 0.3048 0.2032)
							(mid 0.275042 0.275042)
							(end 0.2032 0.3048)
						)
						(arc
							(start -0.2032 0.3048)
							(mid -0.275042 0.275042)
							(end -0.3048 0.2032)
						)
						(arc
							(start -0.3048 -0.2032)
							(mid -0.275042 -0.275042)
							(end -0.2032 -0.3048)
						)
						(arc
							(start 0.2032 -0.3048)
							(mid 0.275042 -0.275042)
							(end 0.3048 -0.2032)
						)
					)
					(width 0)
					(fill yes)
				)
			)
		)
		(pad "2" smd custom
			(at 0 0.4445)
			(size 0.1524 0.1524)
			(layers "B.Cu" "B.Mask" "B.Paste")
			(net "GND")
			(options
				(clearance outline)
				(anchor circle)
			)
			(primitives
				(gr_poly
					(pts
						(arc
							(start 0.3048 0.2032)
							(mid 0.275042 0.275042)
							(end 0.2032 0.3048)
						)
						(arc
							(start -0.2032 0.3048)
							(mid -0.275042 0.275042)
							(end -0.3048 0.2032)
						)
						(arc
							(start -0.3048 -0.2032)
							(mid -0.275042 -0.275042)
							(end -0.2032 -0.3048)
						)
						(arc
							(start 0.2032 -0.3048)
							(mid 0.275042 -0.275042)
							(end 0.3048 -0.2032)
						)
					)
					(width 0)
					(fill yes)
				)
			)
		)
	)
	(footprint ""
		(layer "B.Cu")
		(at 253.5936 -32.9946 90)
		(property "Reference" "C605"
			(at 0 0 90)
			(layer "B.SilkS")
			(hide yes)
			(effects
				(font
					(size 1.27 1.27)
				)
				(justify mirror)
			)
		)
		(property "Value" "SCD1U16V1KX-1-GP"
			(at 2.8321 -1.7399 90)
			(unlocked yes)
			(layer "B.Fab")
			(hide yes)
			(effects
				(font
					(size 1.016 1.016)
					(thickness 0.1524)
				)
				(justify mirror)
			)
		)
		(property "Device Type" "C0201H13"
			(at 2.8321 -3.2639 90)
			(unlocked yes)
			(layer "B.Fab")
			(hide yes)
			(effects
				(font
					(size 1.016 1.016)
					(thickness 0.1524)
				)
				(justify mirror)
			)
		)
		(duplicate_pad_numbers_are_jumpers no)
		(fp_rect
			(start 0.2794 0.6477)
			(end -0.2794 -0.6477)
			(stroke
				(width 0)
				(type default)
			)
			(fill no)
			(layer "B.CrtYd")
		)
		(fp_rect
			(start 0.2794 0.6477)
			(end -0.2794 -0.6477)
			(stroke
				(width 0)
				(type default)
			)
			(fill no)
			(layer "B.Fab")
		)
		(pad "1" smd custom
			(at 0 -0.2794 270)
			(size 0.0762 0.0762)
			(layers "B.Cu" "B.Mask" "B.Paste")
			(net "DUT_AVD_PCIE")
			(options
				(clearance outline)
				(anchor circle)
			)
			(primitives
				(gr_poly
					(pts
						(arc
							(start 0.1524 0.127)
							(mid 0.137521 0.162921)
							(end 0.1016 0.1778)
						)
						(arc
							(start -0.1016 0.1778)
							(mid -0.137521 0.162921)
							(end -0.1524 0.127)
						)
						(arc
							(start -0.1524 -0.127)
							(mid -0.137521 -0.162921)
							(end -0.1016 -0.1778)
						)
						(arc
							(start 0.1016 -0.1778)
							(mid 0.137521 -0.162921)
							(end 0.1524 -0.127)
						)
					)
					(width 0)
					(fill yes)
				)
			)
		)
		(pad "2" smd custom
			(at 0 0.2794 270)
			(size 0.0762 0.0762)
			(layers "B.Cu" "B.Mask" "B.Paste")
			(net "GND")
			(options
				(clearance outline)
				(anchor circle)
			)
			(primitives
				(gr_poly
					(pts
						(arc
							(start 0.1524 0.127)
							(mid 0.137521 0.162921)
							(end 0.1016 0.1778)
						)
						(arc
							(start -0.1016 0.1778)
							(mid -0.137521 0.162921)
							(end -0.1524 0.127)
						)
						(arc
							(start -0.1524 -0.127)
							(mid -0.137521 -0.162921)
							(end -0.1016 -0.1778)
						)
						(arc
							(start 0.1016 -0.1778)
							(mid 0.137521 -0.162921)
							(end 0.1524 -0.127)
						)
					)
					(width 0)
					(fill yes)
				)
			)
		)
	)
)
